# S9S_MB_2U (Grand Teton) — schematic netlist excerpt (pin names and nets, part order shuffled) for the footprints in the layout excerpt that follows; sources: Cadence DE-HDL packaged netlist, KiCad conversion of 03242023_DA0F0TMBIJ0_F0T_Motherboard_J_brd_V01_OCP.brd

R2731  Q_RES  33.2 1% CHIP  pkg 0402LF  page 114 : A = PWRGD_CHD_CPU0_DIMM1 ; B = PWRGD_FAIL_CPU0_CD
R4682  Q_RES  100K 1% CHIP  pkg 0402LF  page 260 : A = PWRGD_P5V ; B = GND
C157  Q_CAP_DIFFBUS  DIFF BUS_0.22UF 6.3V 20% X6S  pkg C0201  page 178 : \1\ = DMI_CPU0_PCH_RX_C_DN<6> ; \2\ = DMI_CPU0_PCH_RX_DN<6>

(kicad_pcb
	(version 20260206)
	(generator "pcbnew")
	(generator_version "10.0")
	(general
		(thickness 1.6)
		(legacy_teardrops no)
	)
	(paper "A4")
	(title_block
		(title "03242023_DA0F0TMBIJ0_F0T_Motherboard_J_brd_V01_OCP.brd")
		(comment 1 "Grand Teton / footprints 5497-5499 of 6105")
	)
	(layers
		(0 "F.Cu" signal "TOP")
		(4 "In1.Cu" signal "GND")
		(6 "In2.Cu" signal "IN1")
		(8 "In3.Cu" signal "GND1")
		(10 "In4.Cu" signal "IN2")
		(12 "In5.Cu" signal "GND2")
		(14 "In6.Cu" signal "IN3")
		(16 "In7.Cu" signal "GND3")
		(18 "In8.Cu" signal "VCC")
		(20 "In9.Cu" signal "VCC1")
		(22 "In10.Cu" signal "GND4")
		(24 "In11.Cu" signal "IN4")
		(26 "In12.Cu" signal "GND5")
		(28 "In13.Cu" signal "IN5")
		(30 "In14.Cu" signal "GND6")
		(32 "In15.Cu" signal "IN6")
		(34 "In16.Cu" signal "GND7")
		(2 "B.Cu" signal "BOTTOM")
		(9 "F.Adhes" user "F.Adhesive")
		(11 "B.Adhes" user "B.Adhesive")
		(13 "F.Paste" user "Package Geometry/Pastemask Top")
		(15 "B.Paste" user "Package Geometry/Pastemask Bottom")
		(5 "F.SilkS" user "Ref Des/Silkscreen Top")
		(7 "B.SilkS" user "Ref Des/Silkscreen Bottom")
		(1 "F.Mask" user "Board Geometry/Soldermask Top")
		(3 "B.Mask" user "Board Geometry/Soldermask Bottom")
		(17 "Dwgs.User" user "User.Drawings")
		(19 "Cmts.User" user "User.Comments")
		(21 "Eco1.User" user "User.Eco1")
		(23 "Eco2.User" user "User.Eco2")
		(25 "Edge.Cuts" user "Board Geometry/Outline")
		(27 "Margin" user)
		(31 "F.CrtYd" user "Package Geometry/Place Bound Top")
		(29 "B.CrtYd" user "Package Geometry/Place Bound Bottom")
		(35 "F.Fab" user "Ref Des/Assembly Top")
		(33 "B.Fab" user "Ref Des/Assembly Bottom")
	)
	(footprint ""
		(layer "B.Cu")
		(at 435.05628 -44.14012 90)
		(property "Reference" "R4682"
			(at 0 0 90)
			(layer "B.SilkS")
			(hide yes)
			(effects
				(font
					(size 1.27 1.27)
				)
				(justify mirror)
			)
		)
		(property "Value" ""
			(at 0 0 90)
			(layer "B.Fab")
			(effects
				(font
					(size 1.27 1.27)
				)
				(justify mirror)
			)
		)
		(duplicate_pad_numbers_are_jumpers no)
		(fp_line
			(start 0.7874 -0.4064)
			(end -0.7874 -0.4064)
			(stroke
				(width 0.1524)
				(type default)
			)
			(layer "B.SilkS")
		)
		(fp_line
			(start -0.7874 -0.4064)
			(end -0.7874 0.4064)
			(stroke
				(width 0.1524)
				(type default)
			)
			(layer "B.SilkS")
		)
		(fp_line
			(start 0.7874 0.4064)
			(end 0.7874 -0.4064)
			(stroke
				(width 0.1524)
				(type default)
			)
			(layer "B.SilkS")
		)
		(fp_line
			(start -0.7874 0.4064)
			(end 0.7874 0.4064)
			(stroke
				(width 0.1524)
				(type default)
			)
			(layer "B.SilkS")
		)
		(fp_line
			(start 0.67945 -0.305054)
			(end 0.12065 -0.305054)
			(stroke
				(width 0.1)
				(type default)
			)
			(layer "B.Fab")
		)
		(fp_line
			(start 0.12065 -0.305054)
			(end 0.12065 -0.2794)
			(stroke
				(width 0.1)
				(type default)
			)
			(layer "B.Fab")
		)
		(fp_line
			(start -0.12065 -0.3048)
			(end -0.67945 -0.3048)
			(stroke
				(width 0.1)
				(type default)
			)
			(layer "B.Fab")
		)
		(fp_line
			(start -0.67945 -0.3048)
			(end -0.67945 0.3048)
			(stroke
				(width 0.1)
				(type default)
			)
			(layer "B.Fab")
		)
		(fp_line
			(start 0.12065 -0.2794)
			(end -0.12065 -0.2794)
			(stroke
				(width 0.1)
				(type default)
			)
			(layer "B.Fab")
		)
		(fp_line
			(start -0.12065 -0.2794)
			(end -0.12065 -0.3048)
			(stroke
				(width 0.1)
				(type default)
			)
			(layer "B.Fab")
		)
		(fp_line
			(start 0.12065 0.2794)
			(end 0.12065 0.3048)
			(stroke
				(width 0.1)
				(type default)
			)
			(layer "B.Fab")
		)
		(fp_line
			(start -0.120396 0.2794)
			(end 0.12065 0.2794)
			(stroke
				(width 0.1)
				(type default)
			)
			(layer "B.Fab")
		)
		(fp_line
			(start 0.67945 0.3048)
			(end 0.67945 -0.305054)
			(stroke
				(width 0.1)
				(type default)
			)
			(layer "B.Fab")
		)
		(fp_line
			(start 0.12065 0.3048)
			(end 0.67945 0.3048)
			(stroke
				(width 0.1)
				(type default)
			)
			(layer "B.Fab")
		)
		(fp_line
			(start -0.120396 0.3048)
			(end -0.120396 0.2794)
			(stroke
				(width 0.1)
				(type default)
			)
			(layer "B.Fab")
		)
		(fp_line
			(start -0.67945 0.3048)
			(end -0.120396 0.3048)
			(stroke
				(width 0.1)
				(type default)
			)
			(layer "B.Fab")
		)
		(pad "1" smd circle
			(at 0.40005 0 270)
			(size 0 0)
			(layers "B.Cu" "B.Mask" "B.Paste")
			(net "PWRGD_P5V")
		)
		(pad "2" smd circle
			(at -0.40005 0 270)
			(size 0 0)
			(layers "B.Cu" "B.Mask" "B.Paste")
			(net "GND")
		)
	)
	(footprint ""
		(layer "B.Cu")
		(at 346.44076 -58.38317 45)
		(property "Reference" "C157"
			(at 0 0 45)
			(layer "B.SilkS")
			(hide yes)
			(effects
				(font
					(size 1.27 1.27)
				)
				(justify mirror)
			)
		)
		(property "Value" ""
			(at 0 0 45)
			(layer "B.Fab")
			(effects
				(font
					(size 1.27 1.27)
				)
				(justify mirror)
			)
		)
		(duplicate_pad_numbers_are_jumpers no)
		(fp_line
			(start -0.299941 -0.15015)
			(end -0.299941 0.15015)
			(stroke
				(width 0.1)
				(type default)
			)
			(layer "B.Fab")
		)
		(fp_line
			(start -0.299941 0.15015)
			(end 0.299941 0.15015)
			(stroke
				(width 0.1)
				(type default)
			)
			(layer "B.Fab")
		)
		(fp_line
			(start 0.299941 -0.15015)
			(end -0.299941 -0.15015)
			(stroke
				(width 0.1)
				(type default)
			)
			(layer "B.Fab")
		)
		(fp_line
			(start 0.299941 0.15015)
			(end 0.299941 -0.15015)
			(stroke
				(width 0.1)
				(type default)
			)
			(layer "B.Fab")
		)
		(pad "1" smd rect
			(at 0.266699 0 225)
			(size 0.3048 0.381)
			(layers "B.Cu" "B.Mask" "B.Paste")
			(net "DMI_CPU0_PCH_RX_C_DN<6>")
		)
		(pad "2" smd rect
			(at -0.266699 0 225)
			(size 0.3048 0.381)
			(layers "B.Cu" "B.Mask" "B.Paste")
			(net "DMI_CPU0_PCH_RX_DN<6>")
		)
	)
	(footprint ""
		(layer "B.Cu")
		(at 260.157214 -319.263776 180)
		(property "Reference" "R2731"
			(at 0 0 0)
			(layer "B.SilkS")
			(hide yes)
			(effects
				(font
					(size 1.27 1.27)
				)
				(justify mirror)
			)
		)
		(property "Value" ""
			(at 0 0 0)
			(layer "B.Fab")
			(effects
				(font
					(size 1.27 1.27)
				)
				(justify mirror)
			)
		)
		(duplicate_pad_numbers_are_jumpers no)
		(fp_line
			(start 0.7874 0.4064)
			(end 0.7874 -0.4064)
			(stroke
				(width 0.1524)
				(type default)
			)
			(layer "B.SilkS")
		)
		(fp_line
			(start 0.7874 -0.4064)
			(end -0.7874 -0.4064)
			(stroke
				(width 0.1524)
				(type default)
			)
			(layer "B.SilkS")
		)
		(fp_line
			(start -0.7874 0.4064)
			(end 0.7874 0.4064)
			(stroke
				(width 0.1524)
				(type default)
			)
			(layer "B.SilkS")
		)
		(fp_line
			(start -0.7874 -0.4064)
			(end -0.7874 0.4064)
			(stroke
				(width 0.1524)
				(type default)
			)
			(layer "B.SilkS")
		)
		(fp_line
			(start 0.67945 0.3048)
			(end 0.67945 -0.305054)
			(stroke
				(width 0.1)
				(type default)
			)
			(layer "B.Fab")
		)
		(fp_line
			(start 0.67945 -0.305054)
			(end 0.12065 -0.305054)
			(stroke
				(width 0.1)
				(type default)
			)
			(layer "B.Fab")
		)
		(fp_line
			(start 0.12065 0.3048)
			(end 0.67945 0.3048)
			(stroke
				(width 0.1)
				(type default)
			)
			(layer "B.Fab")
		)
		(fp_line
			(start 0.12065 0.2794)
			(end 0.12065 0.3048)
			(stroke
				(width 0.1)
				(type default)
			)
			(layer "B.Fab")
		)
		(fp_line
			(start 0.12065 -0.2794)
			(end -0.12065 -0.2794)
			(stroke
				(width 0.1)
				(type default)
			)
			(layer "B.Fab")
		)
		(fp_line
			(start 0.12065 -0.305054)
			(end 0.12065 -0.2794)
			(stroke
				(width 0.1)
				(type default)
			)
			(layer "B.Fab")
		)
		(fp_line
			(start -0.120396 0.3048)
			(end -0.120396 0.2794)
			(stroke
				(width 0.1)
				(type default)
			)
			(layer "B.Fab")
		)
		(fp_line
			(start -0.120396 0.2794)
			(end 0.12065 0.2794)
			(stroke
				(width 0.1)
				(type default)
			)
			(layer "B.Fab")
		)
		(fp_line
			(start -0.12065 -0.2794)
			(end -0.12065 -0.3048)
			(stroke
				(width 0.1)
				(type default)
			)
			(layer "B.Fab")
		)
		(fp_line
			(start -0.12065 -0.3048)
			(end -0.67945 -0.3048)
			(stroke
				(width 0.1)
				(type default)
			)
			(layer "B.Fab")
		)
		(fp_line
			(start -0.67945 0.3048)
			(end -0.120396 0.3048)
			(stroke
				(width 0.1)
				(type default)
			)
			(layer "B.Fab")
		)
		(fp_line
			(start -0.67945 -0.3048)
			(end -0.67945 0.3048)
			(stroke
				(width 0.1)
				(type default)
			)
			(layer "B.Fab")
		)
		(pad "1" smd circle
			(at 0.40005 0)
			(size 0 0)
			(layers "B.Cu" "B.Mask" "B.Paste")
			(net "PWRGD_CHD_CPU0_DIMM1")
		)
		(pad "2" smd circle
			(at -0.40005 0)
			(size 0 0)
			(layers "B.Cu" "B.Mask" "B.Paste")
			(net "PWRGD_FAIL_CPU0_CD")
		)
	)
)
